# BASEBOARD_FAB2 (Tioga Pass) — schematic netlist excerpt (pin names and nets, part order shuffled) for the footprints in the layout excerpt that follows; sources: Cadence DE-HDL packaged netlist, KiCad conversion of Wiwynn_Tioga_Pass_MB.brd

J4B1  SCONN288_H44441004  SCONN  pkg PIP  page 49
  \12v\(1)  = P12V_NVDIMM_DEF
  VSS(93)  = GND
  DQ(4)  = M_D_DQ<5>
  VSS(92)  = GND
  DQ(0)  = M_D_DQ<1>
  VSS(91)  = GND
  DQS9P  = M_D_DQS_DP<9>
  DQS9N  = M_D_DQS_DN<9>
  VSS(90)  = GND
  DQ(6)  = M_D_DQ<7>
  VSS(89)  = GND
  DQ(2)  = M_D_DQ<3>
  VSS(88)  = GND
  DQ(12)  = M_D_DQ<13>
  VSS(87)  = GND
  DQ(8)  = M_D_DQ<9>
  VSS(86)  = GND
  DQS10P  = M_D_DQS_DP<10>
  DQS10N  = M_D_DQS_DN<10>
  VSS(85)  = GND
  DQ(14)  = M_D_DQ<15>
  VSS(84)  = GND
  DQ(10)  = M_D_DQ<11>
  VSS(83)  = GND
  DQ(20)  = M_D_DQ<21>
  VSS(82)  = GND
  DQ(16)  = M_D_DQ<17>
  VSS(81)  = GND
  DQS11P  = M_D_DQS_DP<11>
  DQS11N  = M_D_DQS_DN<11>
  VSS(80)  = GND
  DQ(22)  = M_D_DQ<23>
  VSS(79)  = GND
  DQ(18)  = M_D_DQ<19>
  VSS(78)  = GND
  DQ(28)  = M_D_DQ<29>
  VSS(77)  = GND
  DQ(24)  = M_D_DQ<25>
  VSS(76)  = GND
  DQS12P  = M_D_DQS_DP<12>
  DQS12N  = M_D_DQS_DN<12>
  VSS(75)  = GND
  DQ(30)  = M_D_DQ<31>
  VSS(74)  = GND
  DQ(26)  = M_D_DQ<27>
  VSS(73)  = GND
  CB(4)  = M_D_ECC<5>
  VSS(72)  = GND
  CB(0)  = M_D_ECC<1>
  VSS(71)  = GND
  DQS17P  = M_D_DQS_DP<17>
  DQS17N  = M_D_DQS_DN<17>
  VSS(70)  = GND
  CB(6)  = M_D_ECC<7>
  VSS(69)  = GND
  CB(2)  = M_D_ECC<3>
  VSS(68)  = GND
  RESET_N  = M_DEF_RST_N
  VDD(25)  = PVDDQ_DEF
  CKE(0)  = M_D_CKE<0>
  VDD(24)  = PVDDQ_DEF
  ACT_N  = M_D_ACT_N
  BG(0)  = M_D_BG<0>
  VDD(23)  = PVDDQ_DEF
  A12  = M_D_MA<12>
  A9  = M_D_MA<9>
  VDD(22)  = PVDDQ_DEF
  A8  = M_D_MA<8>
  A6  = M_D_MA<6>
  VDD(21)  = PVDDQ_DEF
  A3  = M_D_MA<3>
  A1  = M_D_MA<1>
  VDD(20)  = PVDDQ_DEF
  CK0P  = M_D_CLK_DP<0>
  CK0N  = M_D_CLK_DN<0>
  VDD(19)  = PVDDQ_DEF
  VTT(1)  = PVTT_DEF
  EVENT_N  = FM_DIMM_EVENT_COD_N
  A0  = M_D_MA<0>
  VDD(18)  = PVDDQ_DEF
  BA(0)  = M_D_BA<0>
  A16_RAS_N  = M_D_MA<16>
  VDD(17)  = PVDDQ_DEF
  S0_N  = M_D_CS_N<0>
  VDD(16)  = PVDDQ_DEF
  A15_CAS_N  = M_D_MA<15>
  ODT(0)  = M_D_ODT<0>
  VDD(15)  = PVDDQ_DEF
  S1_N  = M_D_CS_N<1>
  VDD(14)  = PVDDQ_DEF
  ODT(1)  = M_D_ODT<1>
  VDD(13)  = PVDDQ_DEF
  S2_N_C(0)  = M_D_CS_N<2>
  VSS(67)  = GND
  DQ(36)  = M_D_DQ<37>
  VSS(66)  = GND
  DQ(32)  = M_D_DQ<33>
  VSS(65)  = GND
  DQS13P  = M_D_DQS_DP<13>
  DQS13N  = M_D_DQS_DN<13>
  VSS(64)  = GND
  DQ(38)  = M_D_DQ<39>
  VSS(63)  = GND
  DQ(34)  = M_D_DQ<35>
  VSS(62)  = GND
  DQ(44)  = M_D_DQ<45>
  VSS(61)  = GND
  DQ(40)  = M_D_DQ<41>
  VSS(60)  = GND
  DQS14P  = M_D_DQS_DP<14>
  DQS14N  = M_D_DQS_DN<14>
  VSS(59)  = GND
  DQ(46)  = M_D_DQ<47>
  VSS(58)  = GND
  DQ(42)  = M_D_DQ<43>
  VSS(57)  = GND
  DQ(52)  = M_D_DQ<53>
  VSS(56)  = GND
  DQ(48)  = M_D_DQ<49>
  VSS(55)  = GND
  DQS15P  = M_D_DQS_DP<15>
  DQS15N  = M_D_DQS_DN<15>
  VSS(54)  = GND
  DQ(54)  = M_D_DQ<55>
  VSS(53)  = GND
  DQ(50)  = M_D_DQ<51>
  VSS(52)  = GND
  DQ(60)  = M_D_DQ<61>
  VSS(51)  = GND
  DQ(56)  = M_D_DQ<57>
  VSS(50)  = GND
  DQS16P  = M_D_DQS_DP<16>
  DQS16N  = M_D_DQS_DN<16>
  VSS(49)  = GND
  DQ(62)  = M_D_DQ<63>
  VSS(48)  = GND
  DQ(58)  = M_D_DQ<59>
  VSS(47)  = GND
  SA(0)  = GND
  SA(1)  = GND
  SCL  = SMB_DDR_DEF_VPP_SCL
  VPP(4)  = PVPP_DEF
  VPP(3)  = PVPP_DEF
  RFU(2)  = TP_CH_D_DIMM_D0_RFU_2
  \12v\(0)  = P12V_NVDIMM_DEF
  VREFCA  = M_D_VREF
  VSS(46)  = GND
  DQ(5)  = M_D_DQ<4>
  VSS(45)  = GND
  DQ(1)  = M_D_DQ<0>
  VSS(44)  = GND
  DQS0N  = M_D_DQS_DN<0>
  DQS0P  = M_D_DQS_DP<0>
  VSS(43)  = GND
  DQ(7)  = M_D_DQ<6>
  VSS(42)  = GND
  DQ(3)  = M_D_DQ<2>
  VSS(41)  = GND
  DQ(13)  = M_D_DQ<12>
  VSS(40)  = GND
  DQ(9)  = M_D_DQ<8>
  VSS(39)  = GND
  DQS1N  = M_D_DQS_DN<1>
  DQS1P  = M_D_DQS_DP<1>
  VSS(38)  = GND
  DQ(15)  = M_D_DQ<14>
  VSS(37)  = GND
  DQ(11)  = M_D_DQ<10>
  VSS(36)  = GND
  DQ(21)  = M_D_DQ<20>
  VSS(35)  = GND
  DQ(17)  = M_D_DQ<16>
  VSS(34)  = GND
  DQS2N  = M_D_DQS_DN<2>
  DQS2P  = M_D_DQS_DP<2>
  VSS(33)  = GND
  DQ(23)  = M_D_DQ<22>
  VSS(32)  = GND
  DQ(19)  = M_D_DQ<18>
  VSS(31)  = GND
  DQ(29)  = M_D_DQ<28>
  VSS(30)  = GND
  DQ(25)  = M_D_DQ<24>
  VSS(29)  = GND
  DQS3N  = M_D_DQS_DN<3>
  DQS3P  = M_D_DQS_DP<3>
  VSS(28)  = GND
  DQ(31)  = M_D_DQ<30>
  VSS(27)  = GND
  DQ(27)  = M_D_DQ<26>
  VSS(26)  = GND
  CB(5)  = M_D_ECC<4>
  VSS(25)  = GND
  CB(1)  = M_D_ECC<0>
  VSS(24)  = GND
  DQS8N  = M_D_DQS_DN<8>
  DQS8P  = M_D_DQS_DP<8>
  VSS(23)  = GND
  CB(7)  = M_D_ECC<6>
  VSS(22)  = GND
  CB(3)  = M_D_ECC<2>
  VSS(21)  = GND
  CKE(1)  = M_D_CKE<1>
  VDD(12)  = PVDDQ_DEF
  RFU(0)  = TP_CH_D_DIMM_D0_RFU_0
  VDD(11)  = PVDDQ_DEF
  BG(1)  = M_D_BG<1>
  ALERT_N  = M_D_ALERT_N
  VDD(10)  = PVDDQ_DEF
  A11  = M_D_MA<11>
  A7  = M_D_MA<7>
  VDD(9)  = PVDDQ_DEF
  A5  = M_D_MA<5>
  A4  = M_D_MA<4>
  VDD(8)  = PVDDQ_DEF
  A2  = M_D_MA<2>
  VDD(7)  = PVDDQ_DEF
  CK1P  = M_D_CLK_DP<1>
  CK1N  = M_D_CLK_DN<1>
  VDD(6)  = PVDDQ_DEF
  VTT(0)  = PVTT_DEF
  PAR  = M_D_PAR
  VDD(5)  = PVDDQ_DEF
  BA(1)  = M_D_BA<1>
  A10  = M_D_MA<10>
  VDD(4)  = PVDDQ_DEF
  RFU(1)  = TP_CH_D_DIMM_D0_RFU_1
  A14_WE_N  = M_D_MA<14>
  VDD(3)  = PVDDQ_DEF
  SAVE_N_NC  = FM_ADR_COMPLETE_DEF_N
  VDD(2)  = PVDDQ_DEF
  A13  = M_D_MA<13>
  VDD(1)  = PVDDQ_DEF
  A17  = M_D_MA<17>
  C(2)  = M_D_C<2>
  VDD(0)  = PVDDQ_DEF
  S3_N_C(1)  = M_D_CS_N<3>
  SA(2)  = GND
  VSS(20)  = GND
  DQ(37)  = M_D_DQ<36>
  VSS(19)  = GND
  DQ(33)  = M_D_DQ<32>
  VSS(18)  = GND
  DQS4N  = M_D_DQS_DN<4>
  DQS4P  = M_D_DQS_DP<4>
  VSS(17)  = GND
  DQ(39)  = M_D_DQ<38>
  VSS(16)  = GND
  DQ(35)  = M_D_DQ<34>
  VSS(15)  = GND
  DQ(45)  = M_D_DQ<44>
  VSS(14)  = GND
  DQ(41)  = M_D_DQ<40>
  VSS(13)  = GND
  DQS5N  = M_D_DQS_DN<5>
  DQS5P  = M_D_DQS_DP<5>
  VSS(12)  = GND
  DQ(47)  = M_D_DQ<46>
  VSS(11)  = GND
  DQ(43)  = M_D_DQ<42>
  VSS(10)  = GND
  DQ(53)  = M_D_DQ<52>
  VSS(9)  = GND
  DQ(49)  = M_D_DQ<48>
  VSS(8)  = GND
  DQS6N  = M_D_DQS_DN<6>
  DQS6P  = M_D_DQS_DP<6>
  VSS(7)  = GND
  DQ(55)  = M_D_DQ<54>
  VSS(6)  = GND
  DQ(51)  = M_D_DQ<50>
  VSS(5)  = GND
  DQ(61)  = M_D_DQ<60>
  VSS(4)  = GND
  DQ(57)  = M_D_DQ<56>
  VSS(3)  = GND
  DQS7N  = M_D_DQS_DN<7>
  DQS7P  = M_D_DQS_DP<7>
  VSS(2)  = GND
  DQ(63)  = M_D_DQ<62>
  VSS(1)  = GND
  DQ(59)  = M_D_DQ<58>
  VSS(0)  = GND
  VDDSPD  = PVPP_DEF
  SDA  = SMB_DDR_DEF_VPP_SDA
  VPP(1)  = PVPP_DEF
  VPP(0)  = PVPP_DEF
  VPP(2)  = PVPP_DEF

(kicad_pcb
	(version 20260206)
	(generator "pcbnew")
	(generator_version "10.0")
	(general
		(thickness 1.6)
		(legacy_teardrops no)
	)
	(paper "A4")
	(title_block
		(title "Wiwynn_Tioga_Pass_MB.brd")
		(comment 1 "Tioga Pass / footprint 990 of 4770 (J4B1), pads 102-152 of 291")
	)
	(layers
		(0 "F.Cu" signal "TOP")
		(4 "In1.Cu" signal "L2GND")
		(6 "In2.Cu" signal "L3")
		(8 "In3.Cu" signal "L4GND")
		(10 "In4.Cu" signal "L5")
		(12 "In5.Cu" signal "L6GND")
		(14 "In6.Cu" signal "L7VCC")
		(16 "In7.Cu" signal "L8VCC")
		(18 "In8.Cu" signal "L9GND")
		(20 "In9.Cu" signal "L10")
		(22 "In10.Cu" signal "L11GND")
		(24 "In11.Cu" signal "L12")
		(26 "In12.Cu" signal "L13GND")
		(2 "B.Cu" signal "BOTTOM")
		(9 "F.Adhes" user "F.Adhesive")
		(11 "B.Adhes" user "B.Adhesive")
		(13 "F.Paste" user "Package Geometry/Pastemask Top")
		(15 "B.Paste" user "Package Geometry/Pastemask Bottom")
		(5 "F.SilkS" user "Ref Des/Silkscreen Top")
		(7 "B.SilkS" user "Ref Des/Silkscreen Bottom")
		(1 "F.Mask" user "Board Geometry/Soldermask Top")
		(3 "B.Mask" user "Board Geometry/Soldermask Bottom")
		(17 "Dwgs.User" user "User.Drawings")
		(19 "Cmts.User" user "User.Comments")
		(21 "Eco1.User" user "User.Eco1")
		(23 "Eco2.User" user "User.Eco2")
		(25 "Edge.Cuts" user "Board Geometry/Outline")
		(27 "Margin" user)
		(31 "F.CrtYd" user "Package Geometry/Place Bound Top")
		(29 "B.CrtYd" user "Package Geometry/Place Bound Bottom")
		(35 "F.Fab" user "Ref Des/Assembly Top")
		(33 "B.Fab" user "Ref Des/Assembly Bottom")
	)
	(footprint ""
		(layer "F.Cu")
		(at 194.700398 -133.0706 90)
		(property "Reference" "J4B1"
			(at -5.087112 42.28211 0)
			(unlocked yes)
			(layer "F.SilkS")
			(effects
				(font
					(size 0.7874 0.5842)
					(thickness 0.1524)
				)
				(justify left)
			)
		)
		(property "Value" ""
			(at 0 0 90)
			(layer "F.Fab")
			(effects
				(font
					(size 1.27 1.27)
				)
			)
		)
		(duplicate_pad_numbers_are_jumpers no)
		(pad "99" smd rect
			(at 0 88.399874 90)
			(size 1.8034 0.508)
			(layers "F.Cu" "F.Mask" "F.Paste")
			(net "M_D_DQS_DP<13>")
		)
		(pad "100" smd rect
			(at 0 89.250012 90)
			(size 1.8034 0.508)
			(layers "F.Cu" "F.Mask" "F.Paste")
			(net "M_D_DQS_DN<13>")
		)
		(pad "101" smd rect
			(at 0 90.099896 90)
			(size 1.8034 0.508)
			(layers "F.Cu" "F.Mask" "F.Paste")
			(net "GND")
		)
		(pad "102" smd rect
			(at 0 90.950034 90)
			(size 1.8034 0.508)
			(layers "F.Cu" "F.Mask" "F.Paste")
			(net "M_D_DQ<39>")
		)
		(pad "103" smd rect
			(at 0 91.799918 90)
			(size 1.8034 0.508)
			(layers "F.Cu" "F.Mask" "F.Paste")
			(net "GND")
		)
		(pad "104" smd rect
			(at 0 92.650056 90)
			(size 1.8034 0.508)
			(layers "F.Cu" "F.Mask" "F.Paste")
			(net "M_D_DQ<35>")
		)
		(pad "105" smd rect
			(at 0 93.49994 90)
			(size 1.8034 0.508)
			(layers "F.Cu" "F.Mask" "F.Paste")
			(net "GND")
		)
		(pad "106" smd rect
			(at 0 94.350078 90)
			(size 1.8034 0.508)
			(layers "F.Cu" "F.Mask" "F.Paste")
			(net "M_D_DQ<45>")
		)
		(pad "107" smd rect
			(at 0 95.199962 90)
			(size 1.8034 0.508)
			(layers "F.Cu" "F.Mask" "F.Paste")
			(net "GND")
		)
		(pad "108" smd rect
			(at 0 96.0501 90)
			(size 1.8034 0.508)
			(layers "F.Cu" "F.Mask" "F.Paste")
			(net "M_D_DQ<41>")
		)
		(pad "109" smd rect
			(at 0 96.899984 90)
			(size 1.8034 0.508)
			(layers "F.Cu" "F.Mask" "F.Paste")
			(net "GND")
		)
		(pad "110" smd rect
			(at 0 97.750122 90)
			(size 1.8034 0.508)
			(layers "F.Cu" "F.Mask" "F.Paste")
			(net "M_D_DQS_DP<14>")
		)
		(pad "111" smd rect
			(at 0 98.600006 90)
			(size 1.8034 0.508)
			(layers "F.Cu" "F.Mask" "F.Paste")
			(net "M_D_DQS_DN<14>")
		)
		(pad "112" smd rect
			(at 0 99.44989 90)
			(size 1.8034 0.508)
			(layers "F.Cu" "F.Mask" "F.Paste")
			(net "GND")
		)
		(pad "113" smd rect
			(at 0 100.300028 90)
			(size 1.8034 0.508)
			(layers "F.Cu" "F.Mask" "F.Paste")
			(net "M_D_DQ<47>")
		)
		(pad "114" smd rect
			(at 0 101.149912 90)
			(size 1.8034 0.508)
			(layers "F.Cu" "F.Mask" "F.Paste")
			(net "GND")
		)
		(pad "115" smd rect
			(at 0 102.00005 90)
			(size 1.8034 0.508)
			(layers "F.Cu" "F.Mask" "F.Paste")
			(net "M_D_DQ<43>")
		)
		(pad "116" smd rect
			(at 0 102.849934 90)
			(size 1.8034 0.508)
			(layers "F.Cu" "F.Mask" "F.Paste")
			(net "GND")
		)
		(pad "117" smd rect
			(at 0 103.700072 90)
			(size 1.8034 0.508)
			(layers "F.Cu" "F.Mask" "F.Paste")
			(net "M_D_DQ<53>")
		)
		(pad "118" smd rect
			(at 0 104.549956 90)
			(size 1.8034 0.508)
			(layers "F.Cu" "F.Mask" "F.Paste")
			(net "GND")
		)
		(pad "119" smd rect
			(at 0 105.400094 90)
			(size 1.8034 0.508)
			(layers "F.Cu" "F.Mask" "F.Paste")
			(net "M_D_DQ<49>")
		)
		(pad "120" smd rect
			(at 0 106.249978 90)
			(size 1.8034 0.508)
			(layers "F.Cu" "F.Mask" "F.Paste")
			(net "GND")
		)
		(pad "121" smd rect
			(at 0 107.100116 90)
			(size 1.8034 0.508)
			(layers "F.Cu" "F.Mask" "F.Paste")
			(net "M_D_DQS_DP<15>")
		)
		(pad "122" smd rect
			(at 0 107.95 90)
			(size 1.8034 0.508)
			(layers "F.Cu" "F.Mask" "F.Paste")
			(net "M_D_DQS_DN<15>")
		)
		(pad "123" smd rect
			(at 0 108.799884 90)
			(size 1.8034 0.508)
			(layers "F.Cu" "F.Mask" "F.Paste")
			(net "GND")
		)
		(pad "124" smd rect
			(at 0 109.650022 90)
			(size 1.8034 0.508)
			(layers "F.Cu" "F.Mask" "F.Paste")
			(net "M_D_DQ<55>")
		)
		(pad "125" smd rect
			(at 0 110.499906 90)
			(size 1.8034 0.508)
			(layers "F.Cu" "F.Mask" "F.Paste")
			(net "GND")
		)
		(pad "126" smd rect
			(at 0 111.350044 90)
			(size 1.8034 0.508)
			(layers "F.Cu" "F.Mask" "F.Paste")
			(net "M_D_DQ<51>")
		)
		(pad "127" smd rect
			(at 0 112.199928 90)
			(size 1.8034 0.508)
			(layers "F.Cu" "F.Mask" "F.Paste")
			(net "GND")
		)
		(pad "128" smd rect
			(at 0 113.050066 90)
			(size 1.8034 0.508)
			(layers "F.Cu" "F.Mask" "F.Paste")
			(net "M_D_DQ<61>")
		)
		(pad "129" smd rect
			(at 0 113.89995 90)
			(size 1.8034 0.508)
			(layers "F.Cu" "F.Mask" "F.Paste")
			(net "GND")
		)
		(pad "130" smd rect
			(at 0 114.750088 90)
			(size 1.8034 0.508)
			(layers "F.Cu" "F.Mask" "F.Paste")
			(net "M_D_DQ<57>")
		)
		(pad "131" smd rect
			(at 0 115.599972 90)
			(size 1.8034 0.508)
			(layers "F.Cu" "F.Mask" "F.Paste")
			(net "GND")
		)
		(pad "132" smd rect
			(at 0 116.45011 90)
			(size 1.8034 0.508)
			(layers "F.Cu" "F.Mask" "F.Paste")
			(net "M_D_DQS_DP<16>")
		)
		(pad "133" smd rect
			(at 0 117.299994 90)
			(size 1.8034 0.508)
			(layers "F.Cu" "F.Mask" "F.Paste")
			(net "M_D_DQS_DN<16>")
		)
		(pad "134" smd rect
			(at 0 118.149878 90)
			(size 1.8034 0.508)
			(layers "F.Cu" "F.Mask" "F.Paste")
			(net "GND")
		)
		(pad "135" smd rect
			(at 0 119.000016 90)
			(size 1.8034 0.508)
			(layers "F.Cu" "F.Mask" "F.Paste")
			(net "M_D_DQ<63>")
		)
		(pad "136" smd rect
			(at 0 119.8499 90)
			(size 1.8034 0.508)
			(layers "F.Cu" "F.Mask" "F.Paste")
			(net "GND")
		)
		(pad "137" smd rect
			(at 0 120.700038 90)
			(size 1.8034 0.508)
			(layers "F.Cu" "F.Mask" "F.Paste")
			(net "M_D_DQ<59>")
		)
		(pad "138" smd rect
			(at 0 121.549922 90)
			(size 1.8034 0.508)
			(layers "F.Cu" "F.Mask" "F.Paste")
			(net "GND")
		)
		(pad "139" smd rect
			(at 0 122.40006 90)
			(size 1.8034 0.508)
			(layers "F.Cu" "F.Mask" "F.Paste")
			(net "GND")
		)
		(pad "140" smd rect
			(at 0 123.249944 90)
			(size 1.8034 0.508)
			(layers "F.Cu" "F.Mask" "F.Paste")
			(net "GND")
		)
		(pad "141" smd rect
			(at 0 124.100082 90)
			(size 1.8034 0.508)
			(layers "F.Cu" "F.Mask" "F.Paste")
			(net "SMB_DDR_DEF_VPP_SCL")
		)
		(pad "142" smd rect
			(at 0 124.949966 90)
			(size 1.8034 0.508)
			(layers "F.Cu" "F.Mask" "F.Paste")
			(net "PVPP_DEF")
		)
		(pad "143" smd rect
			(at 0 125.800104 90)
			(size 1.8034 0.508)
			(layers "F.Cu" "F.Mask" "F.Paste")
			(net "PVPP_DEF")
		)
		(pad "144" smd rect
			(at 0 126.649988 90)
			(size 1.8034 0.508)
			(layers "F.Cu" "F.Mask" "F.Paste")
			(net "TP_CH_D_DIMM_D0_RFU_2")
		)
		(pad "145" smd rect
			(at 4.59994 0 90)
			(size 1.8034 0.508)
			(layers "F.Cu" "F.Mask" "F.Paste")
			(net "P12V_NVDIMM_DEF")
		)
		(pad "146" smd rect
			(at 4.59994 0.849884 90)
			(size 1.8034 0.508)
			(layers "F.Cu" "F.Mask" "F.Paste")
			(net "M_D_VREF")
		)
		(pad "147" smd rect
			(at 4.59994 1.700022 90)
			(size 1.8034 0.508)
			(layers "F.Cu" "F.Mask" "F.Paste")
			(net "GND")
		)
		(pad "148" smd rect
			(at 4.59994 2.549906 90)
			(size 1.8034 0.508)
			(layers "F.Cu" "F.Mask" "F.Paste")
			(net "M_D_DQ<4>")
		)
		(pad "149" smd rect
			(at 4.59994 3.400044 90)
			(size 1.8034 0.508)
			(layers "F.Cu" "F.Mask" "F.Paste")
			(net "GND")
		)
	)
)
